# S9S_MB_2U (Grand Teton) — schematic netlist excerpt (pin names and nets, part order shuffled) for the footprints in the layout excerpt that follows; sources: Cadence DE-HDL packaged netlist, KiCad conversion of 03242023_DA0F0TMBIJ0_F0T_Motherboard_J_brd_V01_OCP.brd

X2  TP_TDR_4P_FTS  TP_TDR_4P_DIP EMPTY  pkg TH  page 309
  S1  = TDR_DIFF_85_IN1_DP
  P1  = T1_GND
  P2  = T1_GND
  S2  = TDR_DIFF_85_IN1_DN

R2672  Q_RES  33.2 1% CHIP  pkg 0402LF  page 234 : A = SMB_BMC_SWB_BUF_R_SDA ; B = SMB_BMC_SWB_BUF_SDA

(kicad_pcb
	(version 20260206)
	(generator "pcbnew")
	(generator_version "10.0")
	(general
		(thickness 1.6)
		(legacy_teardrops no)
	)
	(paper "A4")
	(title_block
		(title "03242023_DA0F0TMBIJ0_F0T_Motherboard_J_brd_V01_OCP.brd")
		(comment 1 "Grand Teton / footprints 1132-1133 of 6105")
	)
	(layers
		(0 "F.Cu" signal "TOP")
		(4 "In1.Cu" signal "GND")
		(6 "In2.Cu" signal "IN1")
		(8 "In3.Cu" signal "GND1")
		(10 "In4.Cu" signal "IN2")
		(12 "In5.Cu" signal "GND2")
		(14 "In6.Cu" signal "IN3")
		(16 "In7.Cu" signal "GND3")
		(18 "In8.Cu" signal "VCC")
		(20 "In9.Cu" signal "VCC1")
		(22 "In10.Cu" signal "GND4")
		(24 "In11.Cu" signal "IN4")
		(26 "In12.Cu" signal "GND5")
		(28 "In13.Cu" signal "IN5")
		(30 "In14.Cu" signal "GND6")
		(32 "In15.Cu" signal "IN6")
		(34 "In16.Cu" signal "GND7")
		(2 "B.Cu" signal "BOTTOM")
		(9 "F.Adhes" user "F.Adhesive")
		(11 "B.Adhes" user "B.Adhesive")
		(13 "F.Paste" user "Package Geometry/Pastemask Top")
		(15 "B.Paste" user "Package Geometry/Pastemask Bottom")
		(5 "F.SilkS" user "Ref Des/Silkscreen Top")
		(7 "B.SilkS" user "Ref Des/Silkscreen Bottom")
		(1 "F.Mask" user "Board Geometry/Soldermask Top")
		(3 "B.Mask" user "Board Geometry/Soldermask Bottom")
		(17 "Dwgs.User" user "User.Drawings")
		(19 "Cmts.User" user "User.Comments")
		(21 "Eco1.User" user "User.Eco1")
		(23 "Eco2.User" user "User.Eco2")
		(25 "Edge.Cuts" user "Board Geometry/Outline")
		(27 "Margin" user)
		(31 "F.CrtYd" user "Package Geometry/Place Bound Top")
		(29 "B.CrtYd" user "Package Geometry/Place Bound Bottom")
		(35 "F.Fab" user "Ref Des/Assembly Top")
		(33 "B.Fab" user "Ref Des/Assembly Bottom")
	)
	(footprint ""
		(layer "F.Cu")
		(at 517.258808 -153.2128 -90)
		(property "Reference" "X2"
			(at -1.37668 2.83083 90)
			(unlocked yes)
			(layer "F.SilkS")
			(effects
				(font
					(size 0.7874 0.5842)
					(thickness 0.1524)
				)
				(justify left)
			)
		)
		(property "Value" ""
			(at 0 0 270)
			(layer "F.Fab")
			(effects
				(font
					(size 1.27 1.27)
				)
			)
		)
		(property "Device Type" "TP_TDR_4P_FTS_MPKT4_H025P0200_I"
			(at 1.30175 1.27 0)
			(unlocked yes)
			(layer "F.Fab")
			(hide yes)
			(effects
				(font
					(size 0.635 0.4064)
					(thickness 0.1524)
				)
			)
		)
		(property "User Part Number" "TP15"
			(at 1.30175 1.27 0)
			(unlocked yes)
			(layer "Cmts.User")
			(hide yes)
			(effects
				(font
					(size 0.635 0.4064)
					(thickness 0.1524)
				)
			)
		)
		(duplicate_pad_numbers_are_jumpers no)
		(fp_line
			(start 0 3.81)
			(end 2.54 3.81)
			(stroke
				(width 0.1524)
				(type default)
			)
			(layer "F.SilkS")
		)
		(fp_line
			(start 2.54 3.81)
			(end 2.54 3.6703)
			(stroke
				(width 0.1524)
				(type default)
			)
			(layer "F.SilkS")
		)
		(fp_line
			(start 0 3.175)
			(end 0 3.81)
			(stroke
				(width 0.1524)
				(type default)
			)
			(layer "F.SilkS")
		)
		(fp_line
			(start 2.54 1.4097)
			(end 2.54 1.1303)
			(stroke
				(width 0.1524)
				(type default)
			)
			(layer "F.SilkS")
		)
		(fp_line
			(start 0 0.635)
			(end 0 1.905)
			(stroke
				(width 0.1524)
				(type default)
			)
			(layer "F.SilkS")
		)
		(fp_line
			(start 2.54 -1.1303)
			(end 2.54 -1.27)
			(stroke
				(width 0.1524)
				(type default)
			)
			(layer "F.SilkS")
		)
		(fp_line
			(start 0 -1.27)
			(end 0 -0.635)
			(stroke
				(width 0.1524)
				(type default)
			)
			(layer "F.SilkS")
		)
		(fp_line
			(start 2.54 -1.27)
			(end 0 -1.27)
			(stroke
				(width 0.1524)
				(type default)
			)
			(layer "F.SilkS")
		)
		(fp_poly
			(pts
				(xy -1.224026 0.0635) (xy -2.748026 0.8255) (xy -2.748026 -0.6985)
			)
			(stroke
				(width 0)
				(type default)
			)
			(fill yes)
			(layer "F.SilkS")
		)
		(fp_line
			(start 0 3.81)
			(end 2.54 3.81)
			(stroke
				(width 0.1)
				(type default)
			)
			(layer "F.Fab")
		)
		(fp_line
			(start 2.54 3.81)
			(end 2.54 -1.27)
			(stroke
				(width 0.1)
				(type default)
			)
			(layer "F.Fab")
		)
		(fp_line
			(start 0 -1.27)
			(end 0 3.81)
			(stroke
				(width 0.1)
				(type default)
			)
			(layer "F.Fab")
		)
		(fp_line
			(start 2.54 -1.27)
			(end 0 -1.27)
			(stroke
				(width 0.1)
				(type default)
			)
			(layer "F.Fab")
		)
		(fp_poly
			(pts
				(xy -0.761746 0) (xy -2.285746 -0.762) (xy -2.285746 0.762)
			)
			(stroke
				(width 0)
				(type default)
			)
			(fill yes)
			(layer "F.Fab")
		)
		(pad "1" thru_hole circle
			(at 0 0 270)
			(size 1.0033 1.0033)
			(drill 0.249936)
			(layers "*.Cu" "*.Mask")
			(remove_unused_layers no)
			(net "TDR_DIFF_85_IN1_DP")
			(clearance 0.10795)
			(thermal_gap 0.10795)
			(padstack
				(mode front_inner_back)
				(layer "Inner"
					(shape circle)
					(size 0.8001 0.8001)
					(clearance 0.1524)
				)
				(layer "B.Cu"
					(shape circle)
					(size 1.0033 1.0033)
					(clearance 0.10795)
				)
			)
		)
		(pad "2" thru_hole circle
			(at 2.54 0 270)
			(size 1.9939 1.9939)
			(drill 0.249936)
			(layers "*.Cu" "*.Mask")
			(remove_unused_layers no)
			(net "T1_GND")
			(clearance 0.10795)
			(thermal_gap 0.10795)
			(padstack
				(mode front_inner_back)
				(layer "Inner"
					(shape circle)
					(size 0.8001 0.8001)
					(clearance 0.1524)
				)
				(layer "B.Cu"
					(shape circle)
					(size 1.9939 1.9939)
					(clearance 0.10795)
				)
			)
		)
		(pad "3" thru_hole circle
			(at 2.54 2.54 270)
			(size 1.9939 1.9939)
			(drill 0.249936)
			(layers "*.Cu" "*.Mask")
			(remove_unused_layers no)
			(net "T1_GND")
			(clearance 0.10795)
			(thermal_gap 0.10795)
			(padstack
				(mode front_inner_back)
				(layer "Inner"
					(shape circle)
					(size 0.8001 0.8001)
					(clearance 0.1524)
				)
				(layer "B.Cu"
					(shape circle)
					(size 1.9939 1.9939)
					(clearance 0.10795)
				)
			)
		)
		(pad "4" thru_hole circle
			(at 0 2.54 270)
			(size 1.0033 1.0033)
			(drill 0.249936)
			(layers "*.Cu" "*.Mask")
			(remove_unused_layers no)
			(net "TDR_DIFF_85_IN1_DN")
			(clearance 0.10795)
			(thermal_gap 0.10795)
			(padstack
				(mode front_inner_back)
				(layer "Inner"
					(shape circle)
					(size 0.8001 0.8001)
					(clearance 0.1524)
				)
				(layer "B.Cu"
					(shape circle)
					(size 1.0033 1.0033)
					(clearance 0.10795)
				)
			)
		)
	)
	(footprint ""
		(layer "F.Cu")
		(at 165.53815 -418.514276 -90)
		(property "Reference" "R2672"
			(at 0 0 270)
			(layer "F.SilkS")
			(hide yes)
			(effects
				(font
					(size 1.27 1.27)
				)
			)
		)
		(property "Value" ""
			(at 0 0 270)
			(layer "F.Fab")
			(effects
				(font
					(size 1.27 1.27)
				)
			)
		)
		(duplicate_pad_numbers_are_jumpers no)
		(fp_line
			(start -0.7874 0.4064)
			(end -0.7874 -0.4064)
			(stroke
				(width 0.1524)
				(type default)
			)
			(layer "F.SilkS")
		)
		(fp_line
			(start 0.7874 0.4064)
			(end -0.7874 0.4064)
			(stroke
				(width 0.1524)
				(type default)
			)
			(layer "F.SilkS")
		)
		(fp_line
			(start -0.7874 -0.4064)
			(end 0.7874 -0.4064)
			(stroke
				(width 0.1524)
				(type default)
			)
			(layer "F.SilkS")
		)
		(fp_line
			(start 0.7874 -0.4064)
			(end 0.7874 0.4064)
			(stroke
				(width 0.1524)
				(type default)
			)
			(layer "F.SilkS")
		)
		(fp_line
			(start -0.67945 0.3048)
			(end -0.67945 -0.305054)
			(stroke
				(width 0.1)
				(type default)
			)
			(layer "F.Fab")
		)
		(fp_line
			(start -0.12065 0.3048)
			(end -0.67945 0.3048)
			(stroke
				(width 0.1)
				(type default)
			)
			(layer "F.Fab")
		)
		(fp_line
			(start 0.120396 0.3048)
			(end 0.120396 0.2794)
			(stroke
				(width 0.1)
				(type default)
			)
			(layer "F.Fab")
		)
		(fp_line
			(start 0.67945 0.3048)
			(end 0.120396 0.3048)
			(stroke
				(width 0.1)
				(type default)
			)
			(layer "F.Fab")
		)
		(fp_line
			(start -0.12065 0.2794)
			(end -0.12065 0.3048)
			(stroke
				(width 0.1)
				(type default)
			)
			(layer "F.Fab")
		)
		(fp_line
			(start 0.120396 0.2794)
			(end -0.12065 0.2794)
			(stroke
				(width 0.1)
				(type default)
			)
			(layer "F.Fab")
		)
		(fp_line
			(start -0.12065 -0.2794)
			(end 0.12065 -0.2794)
			(stroke
				(width 0.1)
				(type default)
			)
			(layer "F.Fab")
		)
		(fp_line
			(start 0.12065 -0.2794)
			(end 0.12065 -0.3048)
			(stroke
				(width 0.1)
				(type default)
			)
			(layer "F.Fab")
		)
		(fp_line
			(start 0.12065 -0.3048)
			(end 0.67945 -0.3048)
			(stroke
				(width 0.1)
				(type default)
			)
			(layer "F.Fab")
		)
		(fp_line
			(start 0.67945 -0.3048)
			(end 0.67945 0.3048)
			(stroke
				(width 0.1)
				(type default)
			)
			(layer "F.Fab")
		)
		(fp_line
			(start -0.67945 -0.305054)
			(end -0.12065 -0.305054)
			(stroke
				(width 0.1)
				(type default)
			)
			(layer "F.Fab")
		)
		(fp_line
			(start -0.12065 -0.305054)
			(end -0.12065 -0.2794)
			(stroke
				(width 0.1)
				(type default)
			)
			(layer "F.Fab")
		)
		(pad "1" smd circle
			(at -0.40005 0 270)
			(size 0 0)
			(layers "F.Cu" "F.Mask" "F.Paste")
			(net "SMB_BMC_SWB_BUF_R_SDA")
		)
		(pad "2" smd circle
			(at 0.40005 0 270)
			(size 0 0)
			(layers "F.Cu" "F.Mask" "F.Paste")
			(net "SMB_BMC_SWB_BUF_SDA")
		)
	)
)
